(kicad_pcb
	(version 20260206)
	(generator "pcbnew")
	(generator_version "10.0")
	(general
		(thickness 1.6)
		(legacy_teardrops no)
	)
	(paper "A4")
	(title_block
		(title "12092022_DA0F0TMDCD0_F0T_Management_Board_D_brd_V3_OCP.brd")
		(comment 1 "Grand Teton / footprints 575-581 of 1440")
	)
	(layers
		(0 "F.Cu" signal "TOP")
		(4 "In1.Cu" signal "GND")
		(6 "In2.Cu" signal "IN1")
		(8 "In3.Cu" signal "GND1")
		(10 "In4.Cu" signal "IN2")
		(12 "In5.Cu" signal "VCC")
		(14 "In6.Cu" signal "VCC1")
		(16 "In7.Cu" signal "IN3")
		(18 "In8.Cu" signal "GND2")
		(20 "In9.Cu" signal "IN4")
		(22 "In10.Cu" signal "GND3")
		(2 "B.Cu" signal "BOTTOM")
		(9 "F.Adhes" user "F.Adhesive")
		(11 "B.Adhes" user "B.Adhesive")
		(13 "F.Paste" user "Package Geometry/Pastemask Top")
		(15 "B.Paste" user "Package Geometry/Pastemask Bottom")
		(5 "F.SilkS" user "Ref Des/Silkscreen Top")
		(7 "B.SilkS" user "Ref Des/Silkscreen Bottom")
		(1 "F.Mask" user "Board Geometry/Soldermask Top")
		(3 "B.Mask" user "Board Geometry/Soldermask Bottom")
		(17 "Dwgs.User" user "User.Drawings")
		(19 "Cmts.User" user "User.Comments")
		(21 "Eco1.User" user "User.Eco1")
		(23 "Eco2.User" user "User.Eco2")
		(25 "Edge.Cuts" user "Board Geometry/Outline")
		(27 "Margin" user)
		(31 "F.CrtYd" user "Package Geometry/Place Bound Top")
		(29 "B.CrtYd" user "Package Geometry/Place Bound Bottom")
		(35 "F.Fab" user "Ref Des/Assembly Top")
		(33 "B.Fab" user "Ref Des/Assembly Bottom")
	)
	(footprint ""
		(layer "F.Cu")
		(at 66.5226 -108.0008 -90)
		(property "Reference" "R310"
			(at 0 0 270)
			(layer "F.SilkS")
			(hide yes)
			(effects
				(font
					(size 1.27 1.27)
				)
			)
		)
		(property "Value" ""
			(at 0 0 270)
			(layer "F.Fab")
			(effects
				(font
					(size 1.27 1.27)
				)
			)
		)
		(duplicate_pad_numbers_are_jumpers no)
		(fp_line
			(start -0.7874 0.4064)
			(end -0.7874 -0.4064)
			(stroke
				(width 0.1524)
				(type default)
			)
			(layer "F.SilkS")
		)
		(fp_line
			(start 0.7874 0.4064)
			(end -0.7874 0.4064)
			(stroke
				(width 0.1524)
				(type default)
			)
			(layer "F.SilkS")
		)
		(fp_line
			(start -0.7874 -0.4064)
			(end 0.7874 -0.4064)
			(stroke
				(width 0.1524)
				(type default)
			)
			(layer "F.SilkS")
		)
		(fp_line
			(start 0.7874 -0.4064)
			(end 0.7874 0.4064)
			(stroke
				(width 0.1524)
				(type default)
			)
			(layer "F.SilkS")
		)
		(fp_line
			(start -0.67945 0.3048)
			(end -0.67945 -0.305054)
			(stroke
				(width 0.1)
				(type default)
			)
			(layer "F.Fab")
		)
		(fp_line
			(start -0.12065 0.3048)
			(end -0.67945 0.3048)
			(stroke
				(width 0.1)
				(type default)
			)
			(layer "F.Fab")
		)
		(fp_line
			(start 0.120396 0.3048)
			(end 0.120396 0.2794)
			(stroke
				(width 0.1)
				(type default)
			)
			(layer "F.Fab")
		)
		(fp_line
			(start 0.67945 0.3048)
			(end 0.120396 0.3048)
			(stroke
				(width 0.1)
				(type default)
			)
			(layer "F.Fab")
		)
		(fp_line
			(start -0.12065 0.2794)
			(end -0.12065 0.3048)
			(stroke
				(width 0.1)
				(type default)
			)
			(layer "F.Fab")
		)
		(fp_line
			(start 0.120396 0.2794)
			(end -0.12065 0.2794)
			(stroke
				(width 0.1)
				(type default)
			)
			(layer "F.Fab")
		)
		(fp_line
			(start -0.12065 -0.2794)
			(end 0.12065 -0.2794)
			(stroke
				(width 0.1)
				(type default)
			)
			(layer "F.Fab")
		)
		(fp_line
			(start 0.12065 -0.2794)
			(end 0.12065 -0.3048)
			(stroke
				(width 0.1)
				(type default)
			)
			(layer "F.Fab")
		)
		(fp_line
			(start 0.12065 -0.3048)
			(end 0.67945 -0.3048)
			(stroke
				(width 0.1)
				(type default)
			)
			(layer "F.Fab")
		)
		(fp_line
			(start 0.67945 -0.3048)
			(end 0.67945 0.3048)
			(stroke
				(width 0.1)
				(type default)
			)
			(layer "F.Fab")
		)
		(fp_line
			(start -0.67945 -0.305054)
			(end -0.12065 -0.305054)
			(stroke
				(width 0.1)
				(type default)
			)
			(layer "F.Fab")
		)
		(fp_line
			(start -0.12065 -0.305054)
			(end -0.12065 -0.2794)
			(stroke
				(width 0.1)
				(type default)
			)
			(layer "F.Fab")
		)
		(pad "1" smd circle
			(at -0.40005 0 270)
			(size 0 0)
			(layers "F.Cu" "F.Mask" "F.Paste")
			(net "ESPI_HOST_LPC_BMC_CLK")
		)
		(pad "2" smd circle
			(at 0.40005 0 270)
			(size 0 0)
			(layers "F.Cu" "F.Mask" "F.Paste")
			(net "ESPI_HOST_LPC_BMC_CLK_R")
		)
	)
	(footprint ""
		(layer "F.Cu")
		(at 54.55539 -28.026868 -90)
		(property "Reference" "R212"
			(at 0 0 270)
			(layer "F.SilkS")
			(hide yes)
			(effects
				(font
					(size 1.27 1.27)
				)
			)
		)
		(property "Value" ""
			(at 0 0 270)
			(layer "F.Fab")
			(effects
				(font
					(size 1.27 1.27)
				)
			)
		)
		(duplicate_pad_numbers_are_jumpers no)
		(fp_line
			(start -0.7874 0.4064)
			(end -0.7874 -0.4064)
			(stroke
				(width 0.1524)
				(type default)
			)
			(layer "F.SilkS")
		)
		(fp_line
			(start 0.7874 0.4064)
			(end -0.7874 0.4064)
			(stroke
				(width 0.1524)
				(type default)
			)
			(layer "F.SilkS")
		)
		(fp_line
			(start -0.7874 -0.4064)
			(end 0.7874 -0.4064)
			(stroke
				(width 0.1524)
				(type default)
			)
			(layer "F.SilkS")
		)
		(fp_line
			(start 0.7874 -0.4064)
			(end 0.7874 0.4064)
			(stroke
				(width 0.1524)
				(type default)
			)
			(layer "F.SilkS")
		)
		(fp_line
			(start -0.67945 0.3048)
			(end -0.67945 -0.305054)
			(stroke
				(width 0.1)
				(type default)
			)
			(layer "F.Fab")
		)
		(fp_line
			(start -0.12065 0.3048)
			(end -0.67945 0.3048)
			(stroke
				(width 0.1)
				(type default)
			)
			(layer "F.Fab")
		)
		(fp_line
			(start 0.120396 0.3048)
			(end 0.120396 0.2794)
			(stroke
				(width 0.1)
				(type default)
			)
			(layer "F.Fab")
		)
		(fp_line
			(start 0.67945 0.3048)
			(end 0.120396 0.3048)
			(stroke
				(width 0.1)
				(type default)
			)
			(layer "F.Fab")
		)
		(fp_line
			(start -0.12065 0.2794)
			(end -0.12065 0.3048)
			(stroke
				(width 0.1)
				(type default)
			)
			(layer "F.Fab")
		)
		(fp_line
			(start 0.120396 0.2794)
			(end -0.12065 0.2794)
			(stroke
				(width 0.1)
				(type default)
			)
			(layer "F.Fab")
		)
		(fp_line
			(start -0.12065 -0.2794)
			(end 0.12065 -0.2794)
			(stroke
				(width 0.1)
				(type default)
			)
			(layer "F.Fab")
		)
		(fp_line
			(start 0.12065 -0.2794)
			(end 0.12065 -0.3048)
			(stroke
				(width 0.1)
				(type default)
			)
			(layer "F.Fab")
		)
		(fp_line
			(start 0.12065 -0.3048)
			(end 0.67945 -0.3048)
			(stroke
				(width 0.1)
				(type default)
			)
			(layer "F.Fab")
		)
		(fp_line
			(start 0.67945 -0.3048)
			(end 0.67945 0.3048)
			(stroke
				(width 0.1)
				(type default)
			)
			(layer "F.Fab")
		)
		(fp_line
			(start -0.67945 -0.305054)
			(end -0.12065 -0.305054)
			(stroke
				(width 0.1)
				(type default)
			)
			(layer "F.Fab")
		)
		(fp_line
			(start -0.12065 -0.305054)
			(end -0.12065 -0.2794)
			(stroke
				(width 0.1)
				(type default)
			)
			(layer "F.Fab")
		)
		(pad "1" smd circle
			(at -0.40005 0 270)
			(size 0 0)
			(layers "F.Cu" "F.Mask" "F.Paste")
			(net "P3V3_RGM")
		)
		(pad "2" smd circle
			(at 0.40005 0 270)
			(size 0 0)
			(layers "F.Cu" "F.Mask" "F.Paste")
			(net "PU_25M_BMC_CLK_EN")
		)
	)
	(footprint ""
		(layer "F.Cu")
		(at 40.900604 -87.679784 90)
		(property "Reference" "R485"
			(at 0 0 90)
			(layer "F.SilkS")
			(hide yes)
			(effects
				(font
					(size 1.27 1.27)
				)
			)
		)
		(property "Value" ""
			(at 0 0 90)
			(layer "F.Fab")
			(effects
				(font
					(size 1.27 1.27)
				)
			)
		)
		(duplicate_pad_numbers_are_jumpers no)
		(fp_line
			(start 0.7874 -0.4064)
			(end 0.7874 0.4064)
			(stroke
				(width 0.1524)
				(type default)
			)
			(layer "F.SilkS")
		)
		(fp_line
			(start -0.7874 -0.4064)
			(end 0.7874 -0.4064)
			(stroke
				(width 0.1524)
				(type default)
			)
			(layer "F.SilkS")
		)
		(fp_line
			(start 0.7874 0.4064)
			(end -0.7874 0.4064)
			(stroke
				(width 0.1524)
				(type default)
			)
			(layer "F.SilkS")
		)
		(fp_line
			(start -0.7874 0.4064)
			(end -0.7874 -0.4064)
			(stroke
				(width 0.1524)
				(type default)
			)
			(layer "F.SilkS")
		)
		(fp_line
			(start -0.12065 -0.305054)
			(end -0.12065 -0.2794)
			(stroke
				(width 0.1)
				(type default)
			)
			(layer "F.Fab")
		)
		(fp_line
			(start -0.67945 -0.305054)
			(end -0.12065 -0.305054)
			(stroke
				(width 0.1)
				(type default)
			)
			(layer "F.Fab")
		)
		(fp_line
			(start 0.67945 -0.3048)
			(end 0.67945 0.3048)
			(stroke
				(width 0.1)
				(type default)
			)
			(layer "F.Fab")
		)
		(fp_line
			(start 0.12065 -0.3048)
			(end 0.67945 -0.3048)
			(stroke
				(width 0.1)
				(type default)
			)
			(layer "F.Fab")
		)
		(fp_line
			(start 0.12065 -0.2794)
			(end 0.12065 -0.3048)
			(stroke
				(width 0.1)
				(type default)
			)
			(layer "F.Fab")
		)
		(fp_line
			(start -0.12065 -0.2794)
			(end 0.12065 -0.2794)
			(stroke
				(width 0.1)
				(type default)
			)
			(layer "F.Fab")
		)
		(fp_line
			(start 0.120396 0.2794)
			(end -0.12065 0.2794)
			(stroke
				(width 0.1)
				(type default)
			)
			(layer "F.Fab")
		)
		(fp_line
			(start -0.12065 0.2794)
			(end -0.12065 0.3048)
			(stroke
				(width 0.1)
				(type default)
			)
			(layer "F.Fab")
		)
		(fp_line
			(start 0.67945 0.3048)
			(end 0.120396 0.3048)
			(stroke
				(width 0.1)
				(type default)
			)
			(layer "F.Fab")
		)
		(fp_line
			(start 0.120396 0.3048)
			(end 0.120396 0.2794)
			(stroke
				(width 0.1)
				(type default)
			)
			(layer "F.Fab")
		)
		(fp_line
			(start -0.12065 0.3048)
			(end -0.67945 0.3048)
			(stroke
				(width 0.1)
				(type default)
			)
			(layer "F.Fab")
		)
		(fp_line
			(start -0.67945 0.3048)
			(end -0.67945 -0.305054)
			(stroke
				(width 0.1)
				(type default)
			)
			(layer "F.Fab")
		)
		(pad "1" smd circle
			(at -0.40005 0 90)
			(size 0 0)
			(layers "F.Cu" "F.Mask" "F.Paste")
			(net "SPI_PCH_MUXED_CS0_N")
		)
		(pad "2" smd circle
			(at 0.40005 0 90)
			(size 0 0)
			(layers "F.Cu" "F.Mask" "F.Paste")
			(net "SPI_PCH_CS0_FLASH_R1_N")
		)
	)
	(footprint ""
		(layer "F.Cu")
		(at 11.4554 -61.214 180)
		(property "Reference" "C297"
			(at 0 0 180)
			(layer "F.SilkS")
			(hide yes)
			(effects
				(font
					(size 1.27 1.27)
				)
			)
		)
		(property "Value" ""
			(at 0 0 180)
			(layer "F.Fab")
			(effects
				(font
					(size 1.27 1.27)
				)
			)
		)
		(duplicate_pad_numbers_are_jumpers no)
		(fp_line
			(start 0.7874 0.4064)
			(end -0.7874 0.4064)
			(stroke
				(width 0.1524)
				(type default)
			)
			(layer "F.SilkS")
		)
		(fp_line
			(start 0.7874 -0.4064)
			(end 0.7874 0.4064)
			(stroke
				(width 0.1524)
				(type default)
			)
			(layer "F.SilkS")
		)
		(fp_line
			(start -0.7874 0.4064)
			(end -0.7874 -0.4064)
			(stroke
				(width 0.1524)
				(type default)
			)
			(layer "F.SilkS")
		)
		(fp_line
			(start -0.7874 -0.4064)
			(end 0.7874 -0.4064)
			(stroke
				(width 0.1524)
				(type default)
			)
			(layer "F.SilkS")
		)
		(fp_line
			(start 0.67945 0.3048)
			(end 0.120396 0.3048)
			(stroke
				(width 0.1)
				(type default)
			)
			(layer "F.Fab")
		)
		(fp_line
			(start 0.67945 -0.3048)
			(end 0.67945 0.3048)
			(stroke
				(width 0.1)
				(type default)
			)
			(layer "F.Fab")
		)
		(fp_line
			(start 0.12065 -0.2794)
			(end 0.12065 -0.3048)
			(stroke
				(width 0.1)
				(type default)
			)
			(layer "F.Fab")
		)
		(fp_line
			(start 0.12065 -0.3048)
			(end 0.67945 -0.3048)
			(stroke
				(width 0.1)
				(type default)
			)
			(layer "F.Fab")
		)
		(fp_line
			(start 0.120396 0.3048)
			(end 0.120396 0.2794)
			(stroke
				(width 0.1)
				(type default)
			)
			(layer "F.Fab")
		)
		(fp_line
			(start 0.120396 0.2794)
			(end -0.12065 0.2794)
			(stroke
				(width 0.1)
				(type default)
			)
			(layer "F.Fab")
		)
		(fp_line
			(start -0.12065 0.3048)
			(end -0.67945 0.3048)
			(stroke
				(width 0.1)
				(type default)
			)
			(layer "F.Fab")
		)
		(fp_line
			(start -0.12065 0.2794)
			(end -0.12065 0.3048)
			(stroke
				(width 0.1)
				(type default)
			)
			(layer "F.Fab")
		)
		(fp_line
			(start -0.12065 -0.2794)
			(end 0.12065 -0.2794)
			(stroke
				(width 0.1)
				(type default)
			)
			(layer "F.Fab")
		)
		(fp_line
			(start -0.12065 -0.305054)
			(end -0.12065 -0.2794)
			(stroke
				(width 0.1)
				(type default)
			)
			(layer "F.Fab")
		)
		(fp_line
			(start -0.67945 0.3048)
			(end -0.67945 -0.305054)
			(stroke
				(width 0.1)
				(type default)
			)
			(layer "F.Fab")
		)
		(fp_line
			(start -0.67945 -0.305054)
			(end -0.12065 -0.305054)
			(stroke
				(width 0.1)
				(type default)
			)
			(layer "F.Fab")
		)
		(pad "1" smd circle
			(at -0.40005 0 180)
			(size 0 0)
			(layers "F.Cu" "F.Mask" "F.Paste")
			(net "P3V3_LDO")
		)
		(pad "2" smd circle
			(at 0.40005 0 180)
			(size 0 0)
			(layers "F.Cu" "F.Mask" "F.Paste")
			(net "GND")
		)
	)
	(footprint ""
		(layer "F.Cu")
		(at 48.852836 -109.411008 90)
		(property "Reference" "R101"
			(at 0 0 90)
			(layer "F.SilkS")
			(hide yes)
			(effects
				(font
					(size 1.27 1.27)
				)
			)
		)
		(property "Value" ""
			(at 0 0 90)
			(layer "F.Fab")
			(effects
				(font
					(size 1.27 1.27)
				)
			)
		)
		(duplicate_pad_numbers_are_jumpers no)
		(fp_line
			(start 0.7874 -0.4064)
			(end 0.7874 0.4064)
			(stroke
				(width 0.1524)
				(type default)
			)
			(layer "F.SilkS")
		)
		(fp_line
			(start -0.7874 -0.4064)
			(end 0.7874 -0.4064)
			(stroke
				(width 0.1524)
				(type default)
			)
			(layer "F.SilkS")
		)
		(fp_line
			(start 0.7874 0.4064)
			(end -0.7874 0.4064)
			(stroke
				(width 0.1524)
				(type default)
			)
			(layer "F.SilkS")
		)
		(fp_line
			(start -0.7874 0.4064)
			(end -0.7874 -0.4064)
			(stroke
				(width 0.1524)
				(type default)
			)
			(layer "F.SilkS")
		)
		(fp_line
			(start -0.12065 -0.305054)
			(end -0.12065 -0.2794)
			(stroke
				(width 0.1)
				(type default)
			)
			(layer "F.Fab")
		)
		(fp_line
			(start -0.67945 -0.305054)
			(end -0.12065 -0.305054)
			(stroke
				(width 0.1)
				(type default)
			)
			(layer "F.Fab")
		)
		(fp_line
			(start 0.67945 -0.3048)
			(end 0.67945 0.3048)
			(stroke
				(width 0.1)
				(type default)
			)
			(layer "F.Fab")
		)
		(fp_line
			(start 0.12065 -0.3048)
			(end 0.67945 -0.3048)
			(stroke
				(width 0.1)
				(type default)
			)
			(layer "F.Fab")
		)
		(fp_line
			(start 0.12065 -0.2794)
			(end 0.12065 -0.3048)
			(stroke
				(width 0.1)
				(type default)
			)
			(layer "F.Fab")
		)
		(fp_line
			(start -0.12065 -0.2794)
			(end 0.12065 -0.2794)
			(stroke
				(width 0.1)
				(type default)
			)
			(layer "F.Fab")
		)
		(fp_line
			(start 0.120396 0.2794)
			(end -0.12065 0.2794)
			(stroke
				(width 0.1)
				(type default)
			)
			(layer "F.Fab")
		)
		(fp_line
			(start -0.12065 0.2794)
			(end -0.12065 0.3048)
			(stroke
				(width 0.1)
				(type default)
			)
			(layer "F.Fab")
		)
		(fp_line
			(start 0.67945 0.3048)
			(end 0.120396 0.3048)
			(stroke
				(width 0.1)
				(type default)
			)
			(layer "F.Fab")
		)
		(fp_line
			(start 0.120396 0.3048)
			(end 0.120396 0.2794)
			(stroke
				(width 0.1)
				(type default)
			)
			(layer "F.Fab")
		)
		(fp_line
			(start -0.12065 0.3048)
			(end -0.67945 0.3048)
			(stroke
				(width 0.1)
				(type default)
			)
			(layer "F.Fab")
		)
		(fp_line
			(start -0.67945 0.3048)
			(end -0.67945 -0.305054)
			(stroke
				(width 0.1)
				(type default)
			)
			(layer "F.Fab")
		)
		(pad "1" smd circle
			(at -0.40005 0 90)
			(size 0 0)
			(layers "F.Cu" "F.Mask" "F.Paste")
			(net "P3V3_AUX")
		)
		(pad "2" smd circle
			(at 0.40005 0 90)
			(size 0 0)
			(layers "F.Cu" "F.Mask" "F.Paste")
			(net "RMII_RXER")
		)
	)
	(footprint ""
		(layer "F.Cu")
		(at 16.0782 -62.3062 90)
		(property "Reference" "U51"
			(at 0.9398 1.72847 90)
			(unlocked yes)
			(layer "F.SilkS")
			(effects
				(font
					(size 0.7874 0.5842)
					(thickness 0.1524)
				)
			)
		)
		(property "Value" ""
			(at 0 0 90)
			(layer "F.Fab")
			(effects
				(font
					(size 1.27 1.27)
				)
			)
		)
		(duplicate_pad_numbers_are_jumpers no)
		(fp_line
			(start 1.7272 -1.1176)
			(end 0.254 -1.1176)
			(stroke
				(width 0.1524)
				(type default)
			)
			(layer "F.SilkS")
		)
		(fp_line
			(start 1.7272 -1.1176)
			(end 1.7272 1.1176)
			(stroke
				(width 0.1524)
				(type default)
			)
			(layer "F.SilkS")
		)
		(fp_line
			(start 0.254 -1.1176)
			(end 0 -0.7366)
			(stroke
				(width 0.1524)
				(type default)
			)
			(layer "F.SilkS")
		)
		(fp_line
			(start -0.254 -1.1176)
			(end -1.7272 -1.1176)
			(stroke
				(width 0.1524)
				(type default)
			)
			(layer "F.SilkS")
		)
		(fp_line
			(start 0 -0.7366)
			(end -0.254 -1.1176)
			(stroke
				(width 0.1524)
				(type default)
			)
			(layer "F.SilkS")
		)
		(fp_line
			(start 1.7272 1.1176)
			(end -1.7272 1.1176)
			(stroke
				(width 0.1524)
				(type default)
			)
			(layer "F.SilkS")
		)
		(fp_line
			(start -1.7272 1.1176)
			(end -1.7272 -1.1176)
			(stroke
				(width 0.1524)
				(type default)
			)
			(layer "F.SilkS")
		)
		(fp_poly
			(pts
				(xy -1.905 -0.954786) (xy -2.667 -0.573786) (xy -2.667 -1.335786)
			)
			(stroke
				(width 0)
				(type default)
			)
			(fill yes)
			(layer "F.SilkS")
		)
		(fp_line
			(start 1.5748 -1.1176)
			(end -1.5748 -1.1176)
			(stroke
				(width 0.1)
				(type default)
			)
			(layer "F.Fab")
		)
		(fp_line
			(start -1.5748 -1.1176)
			(end -1.5748 1.1176)
			(stroke
				(width 0.1)
				(type default)
			)
			(layer "F.Fab")
		)
		(fp_line
			(start 1.5748 1.1176)
			(end 1.5748 -1.1176)
			(stroke
				(width 0.1)
				(type default)
			)
			(layer "F.Fab")
		)
		(fp_line
			(start -1.5748 1.1176)
			(end 1.5748 1.1176)
			(stroke
				(width 0.1)
				(type default)
			)
			(layer "F.Fab")
		)
		(fp_poly
			(pts
				(xy -1.9558 -0.649986) (xy -2.7178 -0.268986) (xy -2.7178 -1.030986)
			)
			(stroke
				(width 0)
				(type default)
			)
			(fill yes)
			(layer "F.Fab")
		)
		(pad "1" smd rect
			(at -0.999998 -0.649986)
			(size 0.3556 1.1176)
			(layers "F.Cu" "F.Mask" "F.Paste")
			(net "UART_BIC_DBG_RX_R")
		)
		(pad "2" smd rect
			(at -0.999998 0)
			(size 0.3556 1.1176)
			(layers "F.Cu" "F.Mask" "F.Paste")
			(net "GND")
		)
		(pad "3" smd rect
			(at -0.999998 0.649986)
			(size 0.3556 1.1176)
			(layers "F.Cu" "F.Mask" "F.Paste")
			(net "UART_6_BMC_TXD_R")
		)
		(pad "4" smd rect
			(at 0.999998 0.649986)
			(size 0.3556 1.1176)
			(layers "F.Cu" "F.Mask" "F.Paste")
			(net "UART_BIC_GF_TXD")
		)
		(pad "5" smd rect
			(at 0.999998 0)
			(size 0.3556 1.1176)
			(layers "F.Cu" "F.Mask" "F.Paste")
			(net "P3V3_AUX")
		)
		(pad "6" smd rect
			(at 0.999998 -0.649986)
			(size 0.3556 1.1176)
			(layers "F.Cu" "F.Mask" "F.Paste")
			(net "FM_BIC_DEBUG_SW_N")
		)
	)
	(footprint ""
		(layer "F.Cu")
		(at -6.029198 -137.995152)
		(property "Reference" "DM2"
			(at -0.3937 -0.588518 0)
			(unlocked yes)
			(layer "F.SilkS")
			(effects
				(font
					(size 0.254 0.127)
					(thickness 0.000001)
				)
				(justify left)
			)
		)
		(property "Value" ""
			(at 0 0 0)
			(layer "F.Fab")
			(effects
				(font
					(size 1.27 1.27)
				)
			)
		)
		(duplicate_pad_numbers_are_jumpers no)
		(pad "1" smd circle
			(at 0 0)
			(size 0.762 0.762)
			(layers "F.Cu" "F.Mask" "F.Paste")
			(net "Net_29")
		)
	)
)
